# T6G (Grand Teton) — schematic netlist excerpt (pin names and nets, part order shuffled) for the footprints in the layout excerpt that follows; sources: Cadence DE-HDL packaged netlist, KiCad conversion of 04192023_DAF0TMB3IC0_F0TG_MB_C_brd_V02_OCP.brd

PC523  Q_CAP  470PF 50V 10% X7R  pkg 0402  page 364 : A = P0V9_RETIMER_CPU1_TEMP0 ; B = GND
R4082  Q_RES  10K 1% EMPTY  pkg 0402LF  page 233 : A = CLK_GEN2_SMB_SADR ; B = GND

(kicad_pcb
	(version 20260206)
	(generator "pcbnew")
	(generator_version "10.0")
	(general
		(thickness 1.6)
		(legacy_teardrops no)
	)
	(paper "A4")
	(title_block
		(title "04192023_DAF0TMB3IC0_F0TG_MB_C_brd_V02_OCP.brd")
		(comment 1 "Grand Teton / footprints 1552-1553 of 8354")
	)
	(layers
		(0 "F.Cu" signal "TOP")
		(4 "In1.Cu" signal "GND")
		(6 "In2.Cu" signal "IN1")
		(8 "In3.Cu" signal "GND1")
		(10 "In4.Cu" signal "IN2")
		(12 "In5.Cu" signal "GND2")
		(14 "In6.Cu" signal "IN3")
		(16 "In7.Cu" signal "GND3")
		(18 "In8.Cu" signal "VCC")
		(20 "In9.Cu" signal "VCC1")
		(22 "In10.Cu" signal "GND4")
		(24 "In11.Cu" signal "IN4")
		(26 "In12.Cu" signal "GND5")
		(28 "In13.Cu" signal "IN5")
		(30 "In14.Cu" signal "GND6")
		(32 "In15.Cu" signal "IN6")
		(34 "In16.Cu" signal "GND7")
		(2 "B.Cu" signal "BOTTOM")
		(9 "F.Adhes" user "F.Adhesive")
		(11 "B.Adhes" user "B.Adhesive")
		(13 "F.Paste" user "Package Geometry/Pastemask Top")
		(15 "B.Paste" user "Package Geometry/Pastemask Bottom")
		(5 "F.SilkS" user "Ref Des/Silkscreen Top")
		(7 "B.SilkS" user "Ref Des/Silkscreen Bottom")
		(1 "F.Mask" user "Board Geometry/Soldermask Top")
		(3 "B.Mask" user "Board Geometry/Soldermask Bottom")
		(17 "Dwgs.User" user "User.Drawings")
		(19 "Cmts.User" user "User.Comments")
		(21 "Eco1.User" user "User.Eco1")
		(23 "Eco2.User" user "User.Eco2")
		(25 "Edge.Cuts" user "Board Geometry/Outline")
		(27 "Margin" user)
		(31 "F.CrtYd" user "Package Geometry/Place Bound Top")
		(29 "B.CrtYd" user "Package Geometry/Place Bound Bottom")
		(35 "F.Fab" user "Ref Des/Assembly Top")
		(33 "B.Fab" user "Ref Des/Assembly Bottom")
	)
	(footprint ""
		(layer "F.Cu")
		(at 5.164328 -131.305554 180)
		(property "Reference" "R4082"
			(at 0 0 180)
			(layer "F.SilkS")
			(hide yes)
			(effects
				(font
					(size 1.27 1.27)
				)
			)
		)
		(property "Value" ""
			(at 0 0 180)
			(layer "F.Fab")
			(effects
				(font
					(size 1.27 1.27)
				)
			)
		)
		(duplicate_pad_numbers_are_jumpers no)
		(fp_line
			(start 0.7874 0.4064)
			(end -0.7874 0.4064)
			(stroke
				(width 0.1524)
				(type default)
			)
			(layer "F.SilkS")
		)
		(fp_line
			(start 0.7874 -0.4064)
			(end 0.7874 0.4064)
			(stroke
				(width 0.1524)
				(type default)
			)
			(layer "F.SilkS")
		)
		(fp_line
			(start -0.7874 0.4064)
			(end -0.7874 -0.4064)
			(stroke
				(width 0.1524)
				(type default)
			)
			(layer "F.SilkS")
		)
		(fp_line
			(start -0.7874 -0.4064)
			(end 0.7874 -0.4064)
			(stroke
				(width 0.1524)
				(type default)
			)
			(layer "F.SilkS")
		)
		(fp_line
			(start 0.67945 0.3048)
			(end 0.120396 0.3048)
			(stroke
				(width 0.1)
				(type default)
			)
			(layer "F.Fab")
		)
		(fp_line
			(start 0.67945 -0.3048)
			(end 0.67945 0.3048)
			(stroke
				(width 0.1)
				(type default)
			)
			(layer "F.Fab")
		)
		(fp_line
			(start 0.12065 -0.2794)
			(end 0.12065 -0.3048)
			(stroke
				(width 0.1)
				(type default)
			)
			(layer "F.Fab")
		)
		(fp_line
			(start 0.12065 -0.3048)
			(end 0.67945 -0.3048)
			(stroke
				(width 0.1)
				(type default)
			)
			(layer "F.Fab")
		)
		(fp_line
			(start 0.120396 0.3048)
			(end 0.120396 0.2794)
			(stroke
				(width 0.1)
				(type default)
			)
			(layer "F.Fab")
		)
		(fp_line
			(start 0.120396 0.2794)
			(end -0.12065 0.2794)
			(stroke
				(width 0.1)
				(type default)
			)
			(layer "F.Fab")
		)
		(fp_line
			(start -0.12065 0.3048)
			(end -0.67945 0.3048)
			(stroke
				(width 0.1)
				(type default)
			)
			(layer "F.Fab")
		)
		(fp_line
			(start -0.12065 0.2794)
			(end -0.12065 0.3048)
			(stroke
				(width 0.1)
				(type default)
			)
			(layer "F.Fab")
		)
		(fp_line
			(start -0.12065 -0.2794)
			(end 0.12065 -0.2794)
			(stroke
				(width 0.1)
				(type default)
			)
			(layer "F.Fab")
		)
		(fp_line
			(start -0.12065 -0.305054)
			(end -0.12065 -0.2794)
			(stroke
				(width 0.1)
				(type default)
			)
			(layer "F.Fab")
		)
		(fp_line
			(start -0.67945 0.3048)
			(end -0.67945 -0.305054)
			(stroke
				(width 0.1)
				(type default)
			)
			(layer "F.Fab")
		)
		(fp_line
			(start -0.67945 -0.305054)
			(end -0.12065 -0.305054)
			(stroke
				(width 0.1)
				(type default)
			)
			(layer "F.Fab")
		)
		(pad "1" smd circle
			(at -0.40005 0 180)
			(size 0 0)
			(layers "F.Cu" "F.Mask" "F.Paste")
			(net "CLK_GEN2_SMB_SADR")
		)
		(pad "2" smd circle
			(at 0.40005 0 180)
			(size 0 0)
			(layers "F.Cu" "F.Mask" "F.Paste")
			(net "GND")
		)
	)
	(footprint ""
		(layer "F.Cu")
		(at 10.066782 -410.818584 180)
		(property "Reference" "PC523"
			(at 0 0 180)
			(layer "F.SilkS")
			(hide yes)
			(effects
				(font
					(size 1.27 1.27)
				)
			)
		)
		(property "Value" ""
			(at 0 0 180)
			(layer "F.Fab")
			(effects
				(font
					(size 1.27 1.27)
				)
			)
		)
		(duplicate_pad_numbers_are_jumpers no)
		(fp_line
			(start 0.7874 0.4064)
			(end -0.7874 0.4064)
			(stroke
				(width 0.1524)
				(type default)
			)
			(layer "F.SilkS")
		)
		(fp_line
			(start 0.7874 -0.4064)
			(end 0.7874 0.4064)
			(stroke
				(width 0.1524)
				(type default)
			)
			(layer "F.SilkS")
		)
		(fp_line
			(start -0.7874 0.4064)
			(end -0.7874 -0.4064)
			(stroke
				(width 0.1524)
				(type default)
			)
			(layer "F.SilkS")
		)
		(fp_line
			(start -0.7874 -0.4064)
			(end 0.7874 -0.4064)
			(stroke
				(width 0.1524)
				(type default)
			)
			(layer "F.SilkS")
		)
		(fp_line
			(start 0.67945 0.3048)
			(end 0.120396 0.3048)
			(stroke
				(width 0.1)
				(type default)
			)
			(layer "F.Fab")
		)
		(fp_line
			(start 0.67945 -0.3048)
			(end 0.67945 0.3048)
			(stroke
				(width 0.1)
				(type default)
			)
			(layer "F.Fab")
		)
		(fp_line
			(start 0.12065 -0.2794)
			(end 0.12065 -0.3048)
			(stroke
				(width 0.1)
				(type default)
			)
			(layer "F.Fab")
		)
		(fp_line
			(start 0.12065 -0.3048)
			(end 0.67945 -0.3048)
			(stroke
				(width 0.1)
				(type default)
			)
			(layer "F.Fab")
		)
		(fp_line
			(start 0.120396 0.3048)
			(end 0.120396 0.2794)
			(stroke
				(width 0.1)
				(type default)
			)
			(layer "F.Fab")
		)
		(fp_line
			(start 0.120396 0.2794)
			(end -0.12065 0.2794)
			(stroke
				(width 0.1)
				(type default)
			)
			(layer "F.Fab")
		)
		(fp_line
			(start -0.12065 0.3048)
			(end -0.67945 0.3048)
			(stroke
				(width 0.1)
				(type default)
			)
			(layer "F.Fab")
		)
		(fp_line
			(start -0.12065 0.2794)
			(end -0.12065 0.3048)
			(stroke
				(width 0.1)
				(type default)
			)
			(layer "F.Fab")
		)
		(fp_line
			(start -0.12065 -0.2794)
			(end 0.12065 -0.2794)
			(stroke
				(width 0.1)
				(type default)
			)
			(layer "F.Fab")
		)
		(fp_line
			(start -0.12065 -0.305054)
			(end -0.12065 -0.2794)
			(stroke
				(width 0.1)
				(type default)
			)
			(layer "F.Fab")
		)
		(fp_line
			(start -0.67945 0.3048)
			(end -0.67945 -0.305054)
			(stroke
				(width 0.1)
				(type default)
			)
			(layer "F.Fab")
		)
		(fp_line
			(start -0.67945 -0.305054)
			(end -0.12065 -0.305054)
			(stroke
				(width 0.1)
				(type default)
			)
			(layer "F.Fab")
		)
		(pad "1" smd circle
			(at -0.40005 0 180)
			(size 0 0)
			(layers "F.Cu" "F.Mask" "F.Paste")
			(net "P0V9_RETIMER_CPU1_TEMP0")
		)
		(pad "2" smd circle
			(at 0.40005 0 180)
			(size 0 0)
			(layers "F.Cu" "F.Mask" "F.Paste")
			(net "GND")
		)
	)
)
